(kicad_pcb
	(version 20260206)
	(generator "pcbnew")
	(generator_version "10.0")
	(general
		(thickness 1.6)
		(legacy_teardrops no)
	)
	(paper "A4")
	(title_block
		(title "Bryce Canyon_R.DPB_16317-1_OCP.brd")
		(comment 1 "Bryce Canyon / footprints 984-989 of 2099")
	)
	(layers
		(0 "F.Cu" signal "TOP")
		(4 "In1.Cu" signal "L2GND")
		(6 "In2.Cu" signal "L3")
		(8 "In3.Cu" signal "L4VCC")
		(10 "In4.Cu" signal "L5VCC")
		(12 "In5.Cu" signal "L6")
		(14 "In6.Cu" signal "L7GND")
		(2 "B.Cu" signal "BOTTOM")
		(9 "F.Adhes" user "F.Adhesive")
		(11 "B.Adhes" user "B.Adhesive")
		(13 "F.Paste" user "Package Geometry/Pastemask Top")
		(15 "B.Paste" user "Package Geometry/Pastemask Bottom")
		(5 "F.SilkS" user "Ref Des/Silkscreen Top")
		(7 "B.SilkS" user "Ref Des/Silkscreen Bottom")
		(1 "F.Mask" user "Board Geometry/Soldermask Top")
		(3 "B.Mask" user "Board Geometry/Soldermask Bottom")
		(17 "Dwgs.User" user "User.Drawings")
		(19 "Cmts.User" user "User.Comments")
		(21 "Eco1.User" user "User.Eco1")
		(23 "Eco2.User" user "User.Eco2")
		(25 "Edge.Cuts" user "Board Geometry/Outline")
		(27 "Margin" user)
		(31 "F.CrtYd" user "Package Geometry/Place Bound Top")
		(29 "B.CrtYd" user "Package Geometry/Place Bound Bottom")
		(35 "F.Fab" user "Ref Des/Assembly Top")
		(33 "B.Fab" user "Ref Des/Assembly Bottom")
	)
	(footprint ""
		(layer "F.Cu")
		(at 239.649 -311.912)
		(property "Reference" "R1096"
			(at 0 0 0)
			(layer "F.SilkS")
			(hide yes)
			(effects
				(font
					(size 1.27 1.27)
				)
			)
		)
		(property "Value" "0R2J-2-GP"
			(at 0.064008 -3.993896 0)
			(unlocked yes)
			(layer "F.Fab")
			(hide yes)
			(effects
				(font
					(size 1.016 1.016)
					(thickness 0.1524)
				)
			)
		)
		(property "Device Type" "R402H16"
			(at 0.064008 -5.517896 0)
			(unlocked yes)
			(layer "F.Fab")
			(hide yes)
			(effects
				(font
					(size 1.016 1.016)
					(thickness 0.1524)
				)
			)
		)
		(duplicate_pad_numbers_are_jumpers no)
		(fp_line
			(start -0.508 -0.9398)
			(end -0.508 0.9398)
			(stroke
				(width 0.1524)
				(type default)
			)
			(layer "F.SilkS")
		)
		(fp_line
			(start 0.508 -0.9398)
			(end -0.508 -0.9398)
			(stroke
				(width 0.1524)
				(type default)
			)
			(layer "F.SilkS")
		)
		(fp_rect
			(start -0.508 0.9398)
			(end 0.508 -0.9398)
			(stroke
				(width 0)
				(type default)
			)
			(fill no)
			(layer "F.CrtYd")
		)
		(fp_rect
			(start -0.508 0.9398)
			(end 0.508 -0.9398)
			(stroke
				(width 0)
				(type default)
			)
			(fill no)
			(layer "F.Fab")
		)
		(pad "1" smd custom
			(at 0 -0.4445)
			(size 0.1397 0.1397)
			(layers "F.Cu" "F.Mask" "F.Paste")
			(net "GND")
			(options
				(clearance outline)
				(anchor circle)
			)
			(primitives
				(gr_poly
					(pts
						(arc
							(start -0.1778 -0.2794)
							(mid -0.249642 -0.249642)
							(end -0.2794 -0.1778)
						)
						(arc
							(start -0.2794 0.1778)
							(mid -0.249642 0.249642)
							(end -0.1778 0.2794)
						)
						(arc
							(start 0.1778 0.2794)
							(mid 0.249642 0.249642)
							(end 0.2794 0.1778)
						)
						(arc
							(start 0.2794 -0.1778)
							(mid 0.249642 -0.249642)
							(end 0.1778 -0.2794)
						)
					)
					(width 0)
					(fill yes)
				)
			)
		)
		(pad "2" smd custom
			(at 0 0.4445)
			(size 0.1397 0.1397)
			(layers "F.Cu" "F.Mask" "F.Paste")
			(net "MAX31790_A_WD_ST")
			(options
				(clearance outline)
				(anchor circle)
			)
			(primitives
				(gr_poly
					(pts
						(arc
							(start -0.1778 -0.2794)
							(mid -0.249642 -0.249642)
							(end -0.2794 -0.1778)
						)
						(arc
							(start -0.2794 0.1778)
							(mid -0.249642 0.249642)
							(end -0.1778 0.2794)
						)
						(arc
							(start 0.1778 0.2794)
							(mid 0.249642 0.249642)
							(end 0.2794 0.1778)
						)
						(arc
							(start 0.2794 -0.1778)
							(mid 0.249642 -0.249642)
							(end 0.1778 -0.2794)
						)
					)
					(width 0)
					(fill yes)
				)
			)
		)
	)
	(footprint ""
		(layer "F.Cu")
		(at 180.721 -249.555 90)
		(property "Reference" "R247"
			(at 0 0 90)
			(layer "F.SilkS")
			(hide yes)
			(effects
				(font
					(size 1.27 1.27)
				)
			)
		)
		(property "Value" "4K7R2F-GP"
			(at 0.064008 -3.993896 90)
			(unlocked yes)
			(layer "F.Fab")
			(hide yes)
			(effects
				(font
					(size 1.016 1.016)
					(thickness 0.1524)
				)
			)
		)
		(property "Device Type" "R402H16"
			(at 0.064008 -5.517896 90)
			(unlocked yes)
			(layer "F.Fab")
			(hide yes)
			(effects
				(font
					(size 1.016 1.016)
					(thickness 0.1524)
				)
			)
		)
		(duplicate_pad_numbers_are_jumpers no)
		(fp_line
			(start 0.508 -0.9398)
			(end -0.508 -0.9398)
			(stroke
				(width 0.1524)
				(type default)
			)
			(layer "F.SilkS")
		)
		(fp_line
			(start -0.508 -0.9398)
			(end -0.508 0.9398)
			(stroke
				(width 0.1524)
				(type default)
			)
			(layer "F.SilkS")
		)
		(fp_rect
			(start -0.508 0.9398)
			(end 0.508 -0.9398)
			(stroke
				(width 0)
				(type default)
			)
			(fill no)
			(layer "F.CrtYd")
		)
		(fp_rect
			(start -0.508 0.9398)
			(end 0.508 -0.9398)
			(stroke
				(width 0)
				(type default)
			)
			(fill no)
			(layer "F.Fab")
		)
		(pad "1" smd custom
			(at 0 -0.4445 90)
			(size 0.1397 0.1397)
			(layers "F.Cu" "F.Mask" "F.Paste")
			(net "SW_PWR_R_HDD5")
			(options
				(clearance outline)
				(anchor circle)
			)
			(primitives
				(gr_poly
					(pts
						(arc
							(start -0.1778 -0.2794)
							(mid -0.249642 -0.249642)
							(end -0.2794 -0.1778)
						)
						(arc
							(start -0.2794 0.1778)
							(mid -0.249642 0.249642)
							(end -0.1778 0.2794)
						)
						(arc
							(start 0.1778 0.2794)
							(mid 0.249642 0.249642)
							(end 0.2794 0.1778)
						)
						(arc
							(start 0.2794 -0.1778)
							(mid 0.249642 -0.249642)
							(end 0.1778 -0.2794)
						)
					)
					(width 0)
					(fill yes)
				)
			)
		)
		(pad "2" smd custom
			(at 0 0.4445 90)
			(size 0.1397 0.1397)
			(layers "F.Cu" "F.Mask" "F.Paste")
			(net "GND")
			(options
				(clearance outline)
				(anchor circle)
			)
			(primitives
				(gr_poly
					(pts
						(arc
							(start -0.1778 -0.2794)
							(mid -0.249642 -0.249642)
							(end -0.2794 -0.1778)
						)
						(arc
							(start -0.2794 0.1778)
							(mid -0.249642 0.249642)
							(end -0.1778 0.2794)
						)
						(arc
							(start 0.1778 0.2794)
							(mid 0.249642 0.249642)
							(end 0.2794 0.1778)
						)
						(arc
							(start 0.2794 -0.1778)
							(mid 0.249642 -0.249642)
							(end 0.1778 -0.2794)
						)
					)
					(width 0)
					(fill yes)
				)
			)
		)
	)
	(footprint ""
		(layer "F.Cu")
		(at 375.543826 -102.413562 -90)
		(property "Reference" "R474"
			(at 0 0 270)
			(layer "F.SilkS")
			(hide yes)
			(effects
				(font
					(size 1.27 1.27)
				)
			)
		)
		(property "Value" "4K7R2F-GP"
			(at 0.064008 -3.993896 270)
			(unlocked yes)
			(layer "F.Fab")
			(hide yes)
			(effects
				(font
					(size 1.016 1.016)
					(thickness 0.1524)
				)
			)
		)
		(property "Device Type" "R402H16"
			(at 0.064008 -5.517896 270)
			(unlocked yes)
			(layer "F.Fab")
			(hide yes)
			(effects
				(font
					(size 1.016 1.016)
					(thickness 0.1524)
				)
			)
		)
		(duplicate_pad_numbers_are_jumpers no)
		(fp_line
			(start -0.508 -0.9398)
			(end -0.508 0.9398)
			(stroke
				(width 0.1524)
				(type default)
			)
			(layer "F.SilkS")
		)
		(fp_line
			(start 0.508 -0.9398)
			(end -0.508 -0.9398)
			(stroke
				(width 0.1524)
				(type default)
			)
			(layer "F.SilkS")
		)
		(fp_rect
			(start -0.508 0.9398)
			(end 0.508 -0.9398)
			(stroke
				(width 0)
				(type default)
			)
			(fill no)
			(layer "F.CrtYd")
		)
		(fp_rect
			(start -0.508 0.9398)
			(end 0.508 -0.9398)
			(stroke
				(width 0)
				(type default)
			)
			(fill no)
			(layer "F.Fab")
		)
		(pad "1" smd custom
			(at 0 -0.4445 270)
			(size 0.1397 0.1397)
			(layers "F.Cu" "F.Mask" "F.Paste")
			(net "DRIVE_B_20_FLT_LED")
			(options
				(clearance outline)
				(anchor circle)
			)
			(primitives
				(gr_poly
					(pts
						(arc
							(start -0.1778 -0.2794)
							(mid -0.249642 -0.249642)
							(end -0.2794 -0.1778)
						)
						(arc
							(start -0.2794 0.1778)
							(mid -0.249642 0.249642)
							(end -0.1778 0.2794)
						)
						(arc
							(start 0.1778 0.2794)
							(mid 0.249642 0.249642)
							(end 0.2794 0.1778)
						)
						(arc
							(start 0.2794 -0.1778)
							(mid 0.249642 -0.249642)
							(end 0.1778 -0.2794)
						)
					)
					(width 0)
					(fill yes)
				)
			)
		)
		(pad "2" smd custom
			(at 0 0.4445 270)
			(size 0.1397 0.1397)
			(layers "F.Cu" "F.Mask" "F.Paste")
			(net "GND")
			(options
				(clearance outline)
				(anchor circle)
			)
			(primitives
				(gr_poly
					(pts
						(arc
							(start -0.1778 -0.2794)
							(mid -0.249642 -0.249642)
							(end -0.2794 -0.1778)
						)
						(arc
							(start -0.2794 0.1778)
							(mid -0.249642 0.249642)
							(end -0.1778 0.2794)
						)
						(arc
							(start 0.1778 0.2794)
							(mid 0.249642 0.249642)
							(end 0.2794 0.1778)
						)
						(arc
							(start 0.2794 -0.1778)
							(mid 0.249642 -0.249642)
							(end 0.1778 -0.2794)
						)
					)
					(width 0)
					(fill yes)
				)
			)
		)
	)
	(footprint ""
		(layer "F.Cu")
		(at 115.4176 -27.2034 180)
		(property "Reference" "Q135"
			(at 0 0 180)
			(layer "F.SilkS")
			(hide yes)
			(effects
				(font
					(size 1.27 1.27)
				)
			)
		)
		(property "Value" "AO4406AL-GP"
			(at -3.707384 -1.5367 180)
			(unlocked yes)
			(layer "F.Fab")
			(hide yes)
			(effects
				(font
					(size 1.016 1.016)
					(thickness 0.1524)
				)
			)
		)
		(property "Device Type" "SOIC8H69"
			(at -3.707384 -3.0607 180)
			(unlocked yes)
			(layer "F.Fab")
			(hide yes)
			(effects
				(font
					(size 1.016 1.016)
					(thickness 0.1524)
				)
			)
		)
		(duplicate_pad_numbers_are_jumpers no)
		(fp_line
			(start 2.1336 1.4224)
			(end 2.1336 -1.4224)
			(stroke
				(width 0.1524)
				(type default)
			)
			(layer "F.SilkS")
		)
		(fp_line
			(start 2.1336 -1.4224)
			(end -2.7432 -1.4224)
			(stroke
				(width 0.1524)
				(type default)
			)
			(layer "F.SilkS")
		)
		(fp_line
			(start -2.1844 -0.0508)
			(end -2.7178 0.508)
			(stroke
				(width 0.1524)
				(type default)
			)
			(layer "F.SilkS")
		)
		(fp_line
			(start -2.6289 3.4417)
			(end -2.6289 1.4732)
			(stroke
				(width 0.381)
				(type default)
			)
			(layer "F.SilkS")
		)
		(fp_line
			(start -2.7178 -0.508)
			(end -2.1844 -0.0508)
			(stroke
				(width 0.1524)
				(type default)
			)
			(layer "F.SilkS")
		)
		(fp_line
			(start -2.7432 1.4224)
			(end 2.1336 1.4224)
			(stroke
				(width 0.1524)
				(type default)
			)
			(layer "F.SilkS")
		)
		(fp_line
			(start -2.7432 1.4224)
			(end -2.6416 1.4224)
			(stroke
				(width 0.1524)
				(type default)
			)
			(layer "F.SilkS")
		)
		(fp_line
			(start -2.7432 -1.4224)
			(end -2.7432 1.4224)
			(stroke
				(width 0.1524)
				(type default)
			)
			(layer "F.SilkS")
		)
		(fp_poly
			(pts
				(xy -2.2098 -1.4224) (xy -2.2098 1.4224) (xy 2.2098 1.4224) (xy 2.2098 -1.4224)
			)
			(stroke
				(width 0)
				(type default)
			)
			(fill yes)
			(layer "F.SilkS")
		)
		(fp_rect
			(start -2.450084 2.999994)
			(end 2.450084 -2.999994)
			(stroke
				(width 0)
				(type default)
			)
			(fill no)
			(layer "F.CrtYd")
		)
		(fp_poly
			(pts
				(xy -2.8194 3.6322) (xy -2.8194 -3.6322) (xy 2.8194 -3.6322) (xy 2.8194 1.18364) (xy 2.450084 1.18364)
				(xy 2.450084 -2.999994) (xy -2.450084 -2.999994) (xy -2.450084 2.999994) (xy 2.450084 2.999994)
				(xy 2.450084 1.18618) (xy 2.8194 1.18618) (xy 2.8194 3.6322)
			)
			(stroke
				(width 0)
				(type default)
			)
			(fill no)
			(layer "F.CrtYd")
		)
		(fp_rect
			(start -2.8194 3.6322)
			(end 2.8194 -3.6322)
			(stroke
				(width 0)
				(type default)
			)
			(fill no)
			(layer "F.Fab")
		)
		(pad "1" smd rect
			(at -1.905 2.54 180)
			(size 0.635 1.651)
			(layers "F.Cu" "F.Mask" "F.Paste")
			(net "P5V_HDD27")
		)
		(pad "2" smd rect
			(at -0.635 2.54 180)
			(size 0.635 1.651)
			(layers "F.Cu" "F.Mask" "F.Paste")
			(net "P5V_HDD27")
		)
		(pad "3" smd rect
			(at 0.635 2.54 180)
			(size 0.635 1.651)
			(layers "F.Cu" "F.Mask" "F.Paste")
			(net "P5V_HDD27")
		)
		(pad "4" smd rect
			(at 1.905 2.54 180)
			(size 0.635 1.651)
			(layers "F.Cu" "F.Mask" "F.Paste")
			(net "SW_HDD_P27")
		)
		(pad "5" smd rect
			(at 1.905 -2.54 180)
			(size 0.635 1.651)
			(layers "F.Cu" "F.Mask" "F.Paste")
			(net "P5V_B_2")
		)
		(pad "6" smd rect
			(at 0.635 -2.54 180)
			(size 0.635 1.651)
			(layers "F.Cu" "F.Mask" "F.Paste")
			(net "P5V_B_2")
		)
		(pad "7" smd rect
			(at -0.635 -2.54 180)
			(size 0.635 1.651)
			(layers "F.Cu" "F.Mask" "F.Paste")
			(net "P5V_B_2")
		)
		(pad "8" smd rect
			(at -1.905 -2.54 180)
			(size 0.635 1.651)
			(layers "F.Cu" "F.Mask" "F.Paste")
			(net "P5V_B_2")
		)
	)
	(footprint ""
		(layer "F.Cu")
		(at 149.225 -19.558 90)
		(property "Reference" "R727"
			(at 0 0 90)
			(layer "F.SilkS")
			(hide yes)
			(effects
				(font
					(size 1.27 1.27)
				)
			)
		)
		(property "Value" "4K7R2F-GP"
			(at 0.064008 -3.993896 90)
			(unlocked yes)
			(layer "F.Fab")
			(hide yes)
			(effects
				(font
					(size 1.016 1.016)
					(thickness 0.1524)
				)
			)
		)
		(property "Device Type" "R402H16"
			(at 0.064008 -5.517896 90)
			(unlocked yes)
			(layer "F.Fab")
			(hide yes)
			(effects
				(font
					(size 1.016 1.016)
					(thickness 0.1524)
				)
			)
		)
		(duplicate_pad_numbers_are_jumpers no)
		(fp_line
			(start 0.508 -0.9398)
			(end -0.508 -0.9398)
			(stroke
				(width 0.1524)
				(type default)
			)
			(layer "F.SilkS")
		)
		(fp_line
			(start -0.508 -0.9398)
			(end -0.508 0.9398)
			(stroke
				(width 0.1524)
				(type default)
			)
			(layer "F.SilkS")
		)
		(fp_rect
			(start -0.508 0.9398)
			(end 0.508 -0.9398)
			(stroke
				(width 0)
				(type default)
			)
			(fill no)
			(layer "F.CrtYd")
		)
		(fp_rect
			(start -0.508 0.9398)
			(end 0.508 -0.9398)
			(stroke
				(width 0)
				(type default)
			)
			(fill no)
			(layer "F.Fab")
		)
		(pad "1" smd custom
			(at 0 -0.4445 90)
			(size 0.1397 0.1397)
			(layers "F.Cu" "F.Mask" "F.Paste")
			(net "SW_PWR_R_HDD28")
			(options
				(clearance outline)
				(anchor circle)
			)
			(primitives
				(gr_poly
					(pts
						(arc
							(start -0.1778 -0.2794)
							(mid -0.249642 -0.249642)
							(end -0.2794 -0.1778)
						)
						(arc
							(start -0.2794 0.1778)
							(mid -0.249642 0.249642)
							(end -0.1778 0.2794)
						)
						(arc
							(start 0.1778 0.2794)
							(mid 0.249642 0.249642)
							(end 0.2794 0.1778)
						)
						(arc
							(start 0.2794 -0.1778)
							(mid 0.249642 -0.249642)
							(end 0.1778 -0.2794)
						)
					)
					(width 0)
					(fill yes)
				)
			)
		)
		(pad "2" smd custom
			(at 0 0.4445 90)
			(size 0.1397 0.1397)
			(layers "F.Cu" "F.Mask" "F.Paste")
			(net "GND")
			(options
				(clearance outline)
				(anchor circle)
			)
			(primitives
				(gr_poly
					(pts
						(arc
							(start -0.1778 -0.2794)
							(mid -0.249642 -0.249642)
							(end -0.2794 -0.1778)
						)
						(arc
							(start -0.2794 0.1778)
							(mid -0.249642 0.249642)
							(end -0.1778 0.2794)
						)
						(arc
							(start 0.1778 0.2794)
							(mid 0.249642 0.249642)
							(end 0.2794 0.1778)
						)
						(arc
							(start 0.2794 -0.1778)
							(mid 0.249642 -0.249642)
							(end 0.1778 -0.2794)
						)
					)
					(width 0)
					(fill yes)
				)
			)
		)
	)
	(footprint ""
		(layer "F.Cu")
		(at 476.5294 -131.6228)
		(property "Reference" "R603"
			(at 0 0 0)
			(layer "F.SilkS")
			(hide yes)
			(effects
				(font
					(size 1.27 1.27)
				)
			)
		)
		(property "Value" "220R3F-1-GP"
			(at -0.0254 -2.5146 0)
			(unlocked yes)
			(layer "F.Fab")
			(hide yes)
			(effects
				(font
					(size 1.016 1.016)
					(thickness 0.1524)
				)
			)
		)
		(property "Device Type" "R603H22"
			(at -0.0254 -4.0386 0)
			(unlocked yes)
			(layer "F.Fab")
			(hide yes)
			(effects
				(font
					(size 1.016 1.016)
					(thickness 0.1524)
				)
			)
		)
		(duplicate_pad_numbers_are_jumpers no)
		(fp_line
			(start -0.4826 0)
			(end -0.2032 0)
			(stroke
				(width 0.2032)
				(type default)
			)
			(layer "F.SilkS")
		)
		(fp_line
			(start 0.2032 0)
			(end 0.4826 0)
			(stroke
				(width 0.2032)
				(type default)
			)
			(layer "F.SilkS")
		)
		(fp_rect
			(start -0.5842 1.3335)
			(end 0.5842 -1.3335)
			(stroke
				(width 0)
				(type default)
			)
			(fill no)
			(layer "F.CrtYd")
		)
		(fp_rect
			(start -0.5842 1.3335)
			(end 0.5842 -1.3335)
			(stroke
				(width 0)
				(type default)
			)
			(fill no)
			(layer "F.Fab")
		)
		(pad "1" smd custom
			(at 0 -0.762)
			(size 0.2159 0.2159)
			(layers "F.Cu" "F.Mask" "F.Paste")
			(net "HDD_PRSNT_23")
			(options
				(clearance outline)
				(anchor circle)
			)
			(primitives
				(gr_poly
					(pts
						(arc
							(start -0.3302 -0.4318)
							(mid -0.402042 -0.402042)
							(end -0.4318 -0.3302)
						)
						(arc
							(start -0.4318 0.3302)
							(mid -0.402042 0.402042)
							(end -0.3302 0.4318)
						)
						(arc
							(start 0.3302 0.4318)
							(mid 0.402042 0.402042)
							(end 0.4318 0.3302)
						)
						(arc
							(start 0.4318 -0.3302)
							(mid 0.402042 -0.402042)
							(end 0.3302 -0.4318)
						)
					)
					(width 0)
					(fill yes)
				)
			)
		)
		(pad "2" smd custom
			(at 0 0.762)
			(size 0.2159 0.2159)
			(layers "F.Cu" "F.Mask" "F.Paste")
			(net "DRIVE_B_23_INS")
			(options
				(clearance outline)
				(anchor circle)
			)
			(primitives
				(gr_poly
					(pts
						(arc
							(start -0.3302 -0.4318)
							(mid -0.402042 -0.402042)
							(end -0.4318 -0.3302)
						)
						(arc
							(start -0.4318 0.3302)
							(mid -0.402042 0.402042)
							(end -0.3302 0.4318)
						)
						(arc
							(start 0.3302 0.4318)
							(mid 0.402042 0.402042)
							(end 0.4318 0.3302)
						)
						(arc
							(start 0.4318 -0.3302)
							(mid 0.402042 -0.402042)
							(end 0.3302 -0.4318)
						)
					)
					(width 0)
					(fill yes)
				)
			)
		)
	)
)
